# S9S_MB_2U (Grand Teton) — schematic netlist excerpt (pin names and nets, part order shuffled) for the footprints in the layout excerpt that follows; sources: Cadence DE-HDL packaged netlist, KiCad conversion of 03242023_DA0F0TMBIJ0_F0T_Motherboard_J_brd_V01_OCP.brd

PR370  Q_RES  1K 1% CHIP  pkg 0402LF  page 278 : A = P3V3_AUX ; B = PVCCD_HV_CPU0_PIN_ALT

(kicad_pcb
	(version 20260206)
	(generator "pcbnew")
	(generator_version "10.0")
	(general
		(thickness 1.6)
		(legacy_teardrops no)
	)
	(paper "A4")
	(title_block
		(title "03242023_DA0F0TMBIJ0_F0T_Motherboard_J_brd_V01_OCP.brd")
		(comment 1 "Grand Teton / footprints 2801-2801 of 6105")
	)
	(layers
		(0 "F.Cu" signal "TOP")
		(4 "In1.Cu" signal "GND")
		(6 "In2.Cu" signal "IN1")
		(8 "In3.Cu" signal "GND1")
		(10 "In4.Cu" signal "IN2")
		(12 "In5.Cu" signal "GND2")
		(14 "In6.Cu" signal "IN3")
		(16 "In7.Cu" signal "GND3")
		(18 "In8.Cu" signal "VCC")
		(20 "In9.Cu" signal "VCC1")
		(22 "In10.Cu" signal "GND4")
		(24 "In11.Cu" signal "IN4")
		(26 "In12.Cu" signal "GND5")
		(28 "In13.Cu" signal "IN5")
		(30 "In14.Cu" signal "GND6")
		(32 "In15.Cu" signal "IN6")
		(34 "In16.Cu" signal "GND7")
		(2 "B.Cu" signal "BOTTOM")
		(9 "F.Adhes" user "F.Adhesive")
		(11 "B.Adhes" user "B.Adhesive")
		(13 "F.Paste" user "Package Geometry/Pastemask Top")
		(15 "B.Paste" user "Package Geometry/Pastemask Bottom")
		(5 "F.SilkS" user "Ref Des/Silkscreen Top")
		(7 "B.SilkS" user "Ref Des/Silkscreen Bottom")
		(1 "F.Mask" user "Board Geometry/Soldermask Top")
		(3 "B.Mask" user "Board Geometry/Soldermask Bottom")
		(17 "Dwgs.User" user "User.Drawings")
		(19 "Cmts.User" user "User.Comments")
		(21 "Eco1.User" user "User.Eco1")
		(23 "Eco2.User" user "User.Eco2")
		(25 "Edge.Cuts" user "Board Geometry/Outline")
		(27 "Margin" user)
		(31 "F.CrtYd" user "Package Geometry/Place Bound Top")
		(29 "B.CrtYd" user "Package Geometry/Place Bound Bottom")
		(35 "F.Fab" user "Ref Des/Assembly Top")
		(33 "B.Fab" user "Ref Des/Assembly Bottom")
	)
	(footprint ""
		(layer "F.Cu")
		(at 437.242966 -122.648726 180)
		(property "Reference" "PR370"
			(at 0 0 180)
			(layer "F.SilkS")
			(hide yes)
			(effects
				(font
					(size 1.27 1.27)
				)
			)
		)
		(property "Value" ""
			(at 0 0 180)
			(layer "F.Fab")
			(effects
				(font
					(size 1.27 1.27)
				)
			)
		)
		(duplicate_pad_numbers_are_jumpers no)
		(fp_line
			(start 0.7874 0.4064)
			(end -0.7874 0.4064)
			(stroke
				(width 0.1524)
				(type default)
			)
			(layer "F.SilkS")
		)
		(fp_line
			(start 0.7874 -0.4064)
			(end 0.7874 0.4064)
			(stroke
				(width 0.1524)
				(type default)
			)
			(layer "F.SilkS")
		)
		(fp_line
			(start -0.7874 0.4064)
			(end -0.7874 -0.4064)
			(stroke
				(width 0.1524)
				(type default)
			)
			(layer "F.SilkS")
		)
		(fp_line
			(start -0.7874 -0.4064)
			(end 0.7874 -0.4064)
			(stroke
				(width 0.1524)
				(type default)
			)
			(layer "F.SilkS")
		)
		(fp_line
			(start 0.67945 0.3048)
			(end 0.120396 0.3048)
			(stroke
				(width 0.1)
				(type default)
			)
			(layer "F.Fab")
		)
		(fp_line
			(start 0.67945 -0.3048)
			(end 0.67945 0.3048)
			(stroke
				(width 0.1)
				(type default)
			)
			(layer "F.Fab")
		)
		(fp_line
			(start 0.12065 -0.2794)
			(end 0.12065 -0.3048)
			(stroke
				(width 0.1)
				(type default)
			)
			(layer "F.Fab")
		)
		(fp_line
			(start 0.12065 -0.3048)
			(end 0.67945 -0.3048)
			(stroke
				(width 0.1)
				(type default)
			)
			(layer "F.Fab")
		)
		(fp_line
			(start 0.120396 0.3048)
			(end 0.120396 0.2794)
			(stroke
				(width 0.1)
				(type default)
			)
			(layer "F.Fab")
		)
		(fp_line
			(start 0.120396 0.2794)
			(end -0.12065 0.2794)
			(stroke
				(width 0.1)
				(type default)
			)
			(layer "F.Fab")
		)
		(fp_line
			(start -0.12065 0.3048)
			(end -0.67945 0.3048)
			(stroke
				(width 0.1)
				(type default)
			)
			(layer "F.Fab")
		)
		(fp_line
			(start -0.12065 0.2794)
			(end -0.12065 0.3048)
			(stroke
				(width 0.1)
				(type default)
			)
			(layer "F.Fab")
		)
		(fp_line
			(start -0.12065 -0.2794)
			(end 0.12065 -0.2794)
			(stroke
				(width 0.1)
				(type default)
			)
			(layer "F.Fab")
		)
		(fp_line
			(start -0.12065 -0.305054)
			(end -0.12065 -0.2794)
			(stroke
				(width 0.1)
				(type default)
			)
			(layer "F.Fab")
		)
		(fp_line
			(start -0.67945 0.3048)
			(end -0.67945 -0.305054)
			(stroke
				(width 0.1)
				(type default)
			)
			(layer "F.Fab")
		)
		(fp_line
			(start -0.67945 -0.305054)
			(end -0.12065 -0.305054)
			(stroke
				(width 0.1)
				(type default)
			)
			(layer "F.Fab")
		)
		(pad "1" smd circle
			(at -0.40005 0 180)
			(size 0 0)
			(layers "F.Cu" "F.Mask" "F.Paste")
			(net "P3V3_AUX")
		)
		(pad "2" smd circle
			(at 0.40005 0 180)
			(size 0 0)
			(layers "F.Cu" "F.Mask" "F.Paste")
			(net "PVCCD_HV_CPU0_PIN_ALT")
		)
	)
)
